(kicad_pcb
	(version 20241229)
	(generator "pcbnew")
	(generator_version "9.0")
	(general
		(thickness 1.294)
		(legacy_teardrops no)
	)
	(paper "A3")
	(title_block
		(title "Kintex 410T devboard")
		(date "2024-04-03")
		(rev "1.1.2")
		(comment 9 "footprints 45-49 of 975")
	)
	(layers
		(0 "F.Cu" mixed)
		(4 "In1.Cu" power)
		(6 "In2.Cu" power)
		(8 "In3.Cu" mixed)
		(10 "In4.Cu" power)
		(12 "In5.Cu" mixed)
		(14 "In6.Cu" power)
		(16 "In7.Cu" mixed)
		(18 "In8.Cu" power)
		(2 "B.Cu" mixed)
		(9 "F.Adhes" user "F.Adhesive")
		(11 "B.Adhes" user "B.Adhesive")
		(13 "F.Paste" user)
		(15 "B.Paste" user)
		(5 "F.SilkS" user "F.Silkscreen")
		(7 "B.SilkS" user "B.Silkscreen")
		(1 "F.Mask" user)
		(3 "B.Mask" user)
		(17 "Dwgs.User" user "User.Drawings")
		(19 "Cmts.User" user "User.Comments")
		(21 "Eco1.User" user "User.Eco1")
		(23 "Eco2.User" user "User.Eco2")
		(25 "Edge.Cuts" user)
		(27 "Margin" user)
		(31 "F.CrtYd" user "F.Courtyard")
		(29 "B.CrtYd" user "B.Courtyard")
		(35 "F.Fab" user)
		(33 "B.Fab" user)
	)
	(footprint "antmicro-footprints:Nexperia_SOD128"
		(layer "F.Cu")
		(at 188.625 179.999)
		(property "Reference" "D17"
			(at -3.275 0.001 90)
			(layer "F.SilkS")
			(effects
				(font
					(size 0.7 0.7)
					(thickness 0.15)
				)
			)
		)
		(property "Value" "PMEG3050EP,115"
			(at 0 2.4765 0)
			(layer "F.Fab")
			(effects
				(font
					(size 1 1)
					(thickness 0.15)
				)
			)
		)
		(property "Description" "Schottky Rectifier, 30 V, 5 A, Single, SOD-128, 2 Pins, 360 mV"
			(at 0 0 0)
			(layer "F.Fab")
			(hide yes)
			(effects
				(font
					(size 1.27 1.27)
					(thickness 0.15)
				)
			)
		)
		(property "Author" "Antmicro"
			(at 0 0 0)
			(layer "F.Fab")
			(hide yes)
			(effects
				(font
					(size 1 1)
					(thickness 0.15)
				)
			)
		)
		(property "DNP" "DNP"
			(at 0 0 0)
			(layer "F.Fab")
			(hide yes)
			(effects
				(font
					(size 1 1)
					(thickness 0.15)
				)
			)
		)
		(property "License" "Apache-2.0"
			(at 0 0 0)
			(layer "F.Fab")
			(hide yes)
			(effects
				(font
					(size 1 1)
					(thickness 0.15)
				)
			)
		)
		(property "MPN" "PMEG3050EP,115"
			(at 0 0 0)
			(layer "F.Fab")
			(hide yes)
			(effects
				(font
					(size 1 1)
					(thickness 0.15)
				)
			)
		)
		(property "Manufacturer" "Nexperia"
			(at 0 0 0)
			(layer "F.Fab")
			(hide yes)
			(effects
				(font
					(size 1 1)
					(thickness 0.15)
				)
			)
		)
		(property "dnp" ""
			(at 0 0 0)
			(layer "F.Fab")
			(hide yes)
			(effects
				(font
					(size 1 1)
					(thickness 0.15)
				)
			)
		)
		(property "exclude_from_bom" ""
			(at 0 0 0)
			(layer "F.Fab")
			(hide yes)
			(effects
				(font
					(size 1 1)
					(thickness 0.15)
				)
			)
		)
		(sheetname "Power supply")
		(sheetfile "power-supply.kicad_sch")
		(attr smd exclude_from_bom)
		(fp_line
			(start -2.121 -1.474)
			(end -2.121 -1.287)
			(stroke
				(width 0.15)
				(type solid)
			)
			(layer "F.SilkS")
		)
		(fp_line
			(start -2.121 1.284)
			(end -2.121 1.473)
			(stroke
				(width 0.15)
				(type solid)
			)
			(layer "F.SilkS")
		)
		(fp_line
			(start -2.121 1.473)
			(end 2.12 1.473)
			(stroke
				(width 0.15)
				(type solid)
			)
			(layer "F.SilkS")
		)
		(fp_line
			(start -1.6 -1.4)
			(end -1.6 1.4)
			(stroke
				(width 0.12)
				(type solid)
			)
			(layer "F.SilkS")
		)
		(fp_line
			(start 2.12 -1.474)
			(end -2.121 -1.474)
			(stroke
				(width 0.15)
				(type solid)
			)
			(layer "F.SilkS")
		)
		(fp_line
			(start 2.12 -1.287)
			(end 2.12 -1.474)
			(stroke
				(width 0.15)
				(type solid)
			)
			(layer "F.SilkS")
		)
		(fp_line
			(start 2.12 1.473)
			(end 2.12 1.284)
			(stroke
				(width 0.15)
				(type solid)
			)
			(layer "F.SilkS")
		)
		(fp_rect
			(start -2.8 -1.6)
			(end 2.8 1.6)
			(stroke
				(width 0.05)
				(type solid)
			)
			(fill no)
			(layer "F.CrtYd")
		)
		(fp_line
			(start -2.503 -0.954)
			(end -2.503 0.952)
			(stroke
				(width 0.15)
				(type solid)
			)
			(layer "F.Fab")
		)
		(fp_line
			(start -2.503 0.952)
			(end -1.994 0.952)
			(stroke
				(width 0.15)
				(type solid)
			)
			(layer "F.Fab")
		)
		(fp_line
			(start -1.994 -1.347)
			(end -1.994 1.346)
			(stroke
				(width 0.15)
				(type solid)
			)
			(layer "F.Fab")
		)
		(fp_line
			(start -1.994 -0.954)
			(end -2.503 -0.954)
			(stroke
				(width 0.15)
				(type solid)
			)
			(layer "F.Fab")
		)
		(fp_line
			(start -1.994 -0.675)
			(end -1.321 -1.347)
			(stroke
				(width 0.15)
				(type solid)
			)
			(layer "F.Fab")
		)
		(fp_line
			(start -1.994 0.673)
			(end -1.321 1.346)
			(stroke
				(width 0.15)
				(type solid)
			)
			(layer "F.Fab")
		)
		(fp_line
			(start -1.994 0.952)
			(end -1.994 -0.954)
			(stroke
				(width 0.15)
				(type solid)
			)
			(layer "F.Fab")
		)
		(fp_line
			(start -1.994 1.346)
			(end 1.993 1.346)
			(stroke
				(width 0.15)
				(type solid)
			)
			(layer "F.Fab")
		)
		(fp_line
			(start 1.993 -1.347)
			(end -1.994 -1.347)
			(stroke
				(width 0.15)
				(type solid)
			)
			(layer "F.Fab")
		)
		(fp_line
			(start 1.993 -0.954)
			(end 1.993 0.952)
			(stroke
				(width 0.15)
				(type solid)
			)
			(layer "F.Fab")
		)
		(fp_line
			(start 1.993 0.952)
			(end 2.5 0.952)
			(stroke
				(width 0.15)
				(type solid)
			)
			(layer "F.Fab")
		)
		(fp_line
			(start 1.993 1.346)
			(end 1.993 -1.347)
			(stroke
				(width 0.15)
				(type solid)
			)
			(layer "F.Fab")
		)
		(fp_line
			(start 2.5 -0.954)
			(end 1.993 -0.954)
			(stroke
				(width 0.15)
				(type solid)
			)
			(layer "F.Fab")
		)
		(fp_line
			(start 2.5 0.952)
			(end 2.5 -0.954)
			(stroke
				(width 0.15)
				(type solid)
			)
			(layer "F.Fab")
		)
		(pad "1" smd rect
			(at -2.298 0)
			(size 0.8096 1.905)
			(layers "F.Cu" "F.Mask" "F.Paste")
			(net 702 "VDC")
			(pinfunction "1")
			(pintype "passive")
		)
		(pad "2" smd rect
			(at 2.297 0)
			(size 0.8096 1.905)
			(layers "F.Cu" "F.Mask" "F.Paste")
			(net 956 "/DC-DC Converters/POE_DC")
			(pinfunction "2")
			(pintype "passive")
		)
	)
	(footprint "antmicro-footprints:C_0402_1005Metric"
		(layer "F.Cu")
		(at 203.7625 88.3365 -90)
		(descr "Capacitor SMD 0402")
		(tags "capacitor SMD 0402")
		(property "Reference" "C277"
			(at -0.8865 -0.3875 270)
			(layer "F.SilkS")
			(effects
				(font
					(size 0.7 0.7)
					(thickness 0.15)
				)
				(justify left bottom)
			)
		)
		(property "Value" "C_100n_0402"
			(at 0 1.169 270)
			(layer "F.Fab")
			(effects
				(font
					(size 0.7 0.7)
					(thickness 0.15)
				)
				(justify left bottom)
			)
		)
		(property "Description" "SMD Multilayer Ceramic Capacitor, 0.1 µF, 50 V, 0402 [1005 Metric], ± 10%, X5R, GRM Series"
			(at 0 0 270)
			(layer "F.Fab")
			(hide yes)
			(effects
				(font
					(size 1.27 1.27)
					(thickness 0.15)
				)
			)
		)
		(property "Author" "Antmicro"
			(at 115.426 292.099 0)
			(layer "F.Fab")
			(hide yes)
			(effects
				(font
					(size 1 1)
					(thickness 0.15)
				)
			)
		)
		(property "Dielectric" "X5R"
			(at 115.426 292.099 0)
			(layer "F.Fab")
			(hide yes)
			(effects
				(font
					(size 1 1)
					(thickness 0.15)
				)
			)
		)
		(property "License" "Apache-2.0"
			(at 115.426 292.099 0)
			(layer "F.Fab")
			(hide yes)
			(effects
				(font
					(size 1 1)
					(thickness 0.15)
				)
			)
		)
		(property "MPN" "GRM155R61H104KE14D"
			(at 115.426 292.099 0)
			(layer "F.Fab")
			(hide yes)
			(effects
				(font
					(size 1 1)
					(thickness 0.15)
				)
			)
		)
		(property "Manufacturer" "Murata"
			(at 115.426 292.099 0)
			(layer "F.Fab")
			(hide yes)
			(effects
				(font
					(size 1 1)
					(thickness 0.15)
				)
			)
		)
		(property "Val" "100n"
			(at 115.426 292.099 0)
			(layer "F.Fab")
			(hide yes)
			(effects
				(font
					(size 1 1)
					(thickness 0.15)
				)
			)
		)
		(property "Voltage" "50V"
			(at 115.426 292.099 0)
			(layer "F.Fab")
			(hide yes)
			(effects
				(font
					(size 1 1)
					(thickness 0.15)
				)
			)
		)
		(sheetname "HDMI + Ethernet")
		(sheetfile "hdmi-ethernet.kicad_sch")
		(attr smd)
		(fp_rect
			(start -0.925 -0.47)
			(end 0.925 0.47)
			(stroke
				(width 0.05)
				(type default)
			)
			(fill no)
			(layer "F.CrtYd")
		)
		(fp_line
			(start -0.494 0.248)
			(end -0.494 -0.25)
			(stroke
				(width 0.15)
				(type solid)
			)
			(layer "F.Fab")
		)
		(fp_line
			(start 0.504 0.248)
			(end -0.494 0.248)
			(stroke
				(width 0.15)
				(type solid)
			)
			(layer "F.Fab")
		)
		(fp_line
			(start -0.494 -0.25)
			(end 0.504 -0.25)
			(stroke
				(width 0.15)
				(type solid)
			)
			(layer "F.Fab")
		)
		(fp_line
			(start 0.504 -0.25)
			(end 0.504 0.248)
			(stroke
				(width 0.15)
				(type solid)
			)
			(layer "F.Fab")
		)
		(pad "1" smd roundrect
			(at -0.48 0 270)
			(size 0.59 0.64)
			(layers "F.Cu" "F.Mask" "F.Paste")
			(roundrect_rratio 0.25)
			(net 1 "GND")
			(pintype "passive")
		)
		(pad "2" smd roundrect
			(at 0.48 0 270)
			(size 0.59 0.64)
			(layers "F.Cu" "F.Mask" "F.Paste")
			(roundrect_rratio 0.25)
			(net 727 "+1V2")
			(pintype "passive")
		)
	)
	(footprint "antmicro-footprints:C_0402_1005Metric"
		(layer "F.Cu")
		(at 199.901 107.199 180)
		(descr "Capacitor SMD 0402")
		(tags "capacitor SMD 0402")
		(property "Reference" "C227"
			(at -0.899 -0.401 180)
			(layer "F.SilkS")
			(effects
				(font
					(size 0.7 0.7)
					(thickness 0.15)
				)
				(justify left bottom)
			)
		)
		(property "Value" "C_100n_0402"
			(at 0 1.169 180)
			(layer "F.Fab")
			(effects
				(font
					(size 0.7 0.7)
					(thickness 0.15)
				)
				(justify left bottom)
			)
		)
		(property "Description" "SMD Multilayer Ceramic Capacitor, 0.1 µF, 50 V, 0402 [1005 Metric], ± 10%, X5R, GRM Series"
			(at 0 0 180)
			(layer "F.Fab")
			(hide yes)
			(effects
				(font
					(size 1.27 1.27)
					(thickness 0.15)
				)
			)
		)
		(property "Author" "Antmicro"
			(at 399.802 214.398 0)
			(layer "F.Fab")
			(hide yes)
			(effects
				(font
					(size 1 1)
					(thickness 0.15)
				)
			)
		)
		(property "Dielectric" "X5R"
			(at 399.802 214.398 0)
			(layer "F.Fab")
			(hide yes)
			(effects
				(font
					(size 1 1)
					(thickness 0.15)
				)
			)
		)
		(property "License" "Apache-2.0"
			(at 399.802 214.398 0)
			(layer "F.Fab")
			(hide yes)
			(effects
				(font
					(size 1 1)
					(thickness 0.15)
				)
			)
		)
		(property "MPN" "GRM155R61H104KE14D"
			(at 399.802 214.398 0)
			(layer "F.Fab")
			(hide yes)
			(effects
				(font
					(size 1 1)
					(thickness 0.15)
				)
			)
		)
		(property "Manufacturer" "Murata"
			(at 399.802 214.398 0)
			(layer "F.Fab")
			(hide yes)
			(effects
				(font
					(size 1 1)
					(thickness 0.15)
				)
			)
		)
		(property "Val" "100n"
			(at 399.802 214.398 0)
			(layer "F.Fab")
			(hide yes)
			(effects
				(font
					(size 1 1)
					(thickness 0.15)
				)
			)
		)
		(property "Voltage" "50V"
			(at 399.802 214.398 0)
			(layer "F.Fab")
			(hide yes)
			(effects
				(font
					(size 1 1)
					(thickness 0.15)
				)
			)
		)
		(sheetname "USB PHY")
		(sheetfile "usb-phy.kicad_sch")
		(attr smd)
		(fp_rect
			(start -0.925 -0.47)
			(end 0.925 0.47)
			(stroke
				(width 0.05)
				(type default)
			)
			(fill no)
			(layer "F.CrtYd")
		)
		(fp_line
			(start 0.504 0.248)
			(end -0.494 0.248)
			(stroke
				(width 0.15)
				(type solid)
			)
			(layer "F.Fab")
		)
		(fp_line
			(start 0.504 -0.25)
			(end 0.504 0.248)
			(stroke
				(width 0.15)
				(type solid)
			)
			(layer "F.Fab")
		)
		(fp_line
			(start -0.494 0.248)
			(end -0.494 -0.25)
			(stroke
				(width 0.15)
				(type solid)
			)
			(layer "F.Fab")
		)
		(fp_line
			(start -0.494 -0.25)
			(end 0.504 -0.25)
			(stroke
				(width 0.15)
				(type solid)
			)
			(layer "F.Fab")
		)
		(pad "1" smd roundrect
			(at -0.48 0 180)
			(size 0.59 0.64)
			(layers "F.Cu" "F.Mask" "F.Paste")
			(roundrect_rratio 0.25)
			(net 1 "GND")
			(pintype "passive")
		)
		(pad "2" smd roundrect
			(at 0.48 0 180)
			(size 0.59 0.64)
			(layers "F.Cu" "F.Mask" "F.Paste")
			(roundrect_rratio 0.25)
			(net 709 "/USB PHY/USB_HOST_VBCOMP")
			(pintype "passive")
		)
	)
	(footprint "antmicro-footprints:R_0402_1005Metric"
		(layer "F.Cu")
		(at 225.55 149.7 90)
		(descr "Resistor SMD 0402")
		(tags "resistor SMD 0402")
		(property "Reference" "R241"
			(at -1.4 1.3 90)
			(layer "F.SilkS")
			(effects
				(font
					(size 0.7 0.7)
					(thickness 0.15)
				)
				(justify left bottom)
			)
		)
		(property "Value" "R_1M_0402"
			(at 0 1.4 90)
			(layer "F.Fab")
			(effects
				(font
					(size 0.7 0.7)
					(thickness 0.15)
				)
				(justify left bottom)
			)
		)
		(property "Description" "SMD Chip Resistor, 1 Mohm, ± 1%, 62.5 mW, 0402 [1005 Metric], Thick Film, General Purpose"
			(at 0 0 90)
			(layer "F.Fab")
			(hide yes)
			(effects
				(font
					(size 1.27 1.27)
					(thickness 0.15)
				)
			)
		)
		(property "Author" "Antmicro"
			(at 375.25 -75.85 0)
			(layer "F.Fab")
			(hide yes)
			(effects
				(font
					(size 1 1)
					(thickness 0.15)
				)
			)
		)
		(property "License" "Apache-2.0"
			(at 375.25 -75.85 0)
			(layer "F.Fab")
			(hide yes)
			(effects
				(font
					(size 1 1)
					(thickness 0.15)
				)
			)
		)
		(property "MPN" "CR0402-FX-1004GLF"
			(at 375.25 -75.85 0)
			(layer "F.Fab")
			(hide yes)
			(effects
				(font
					(size 1 1)
					(thickness 0.15)
				)
			)
		)
		(property "Manufacturer" "Bourns"
			(at 375.25 -75.85 0)
			(layer "F.Fab")
			(hide yes)
			(effects
				(font
					(size 1 1)
					(thickness 0.15)
				)
			)
		)
		(property "Tolerance" "1%"
			(at 375.25 -75.85 0)
			(layer "F.Fab")
			(hide yes)
			(effects
				(font
					(size 1 1)
					(thickness 0.15)
				)
			)
		)
		(property "Val" "1M"
			(at 375.25 -75.85 0)
			(layer "F.Fab")
			(hide yes)
			(effects
				(font
					(size 1 1)
					(thickness 0.15)
				)
			)
		)
		(sheetname "HDMI + Ethernet")
		(sheetfile "hdmi-ethernet.kicad_sch")
		(attr smd)
		(fp_rect
			(start -0.925 -0.47)
			(end 0.925 0.47)
			(stroke
				(width 0.05)
				(type default)
			)
			(fill no)
			(layer "F.CrtYd")
		)
		(fp_rect
			(start -0.5 -0.25)
			(end 0.5 0.25)
			(stroke
				(width 0.15)
				(type solid)
			)
			(fill no)
			(layer "F.Fab")
		)
		(pad "1" smd roundrect
			(at -0.48 0 90)
			(size 0.59 0.64)
			(layers "F.Cu" "F.Mask" "F.Paste")
			(roundrect_rratio 0.25)
			(net 719 "/HDMI + Ethernet/ETH_XO")
			(pintype "passive")
		)
		(pad "2" smd roundrect
			(at 0.48 0 90)
			(size 0.59 0.64)
			(layers "F.Cu" "F.Mask" "F.Paste")
			(roundrect_rratio 0.25)
			(net 716 "/HDMI + Ethernet/ETH_XI")
			(pintype "passive")
		)
	)
	(footprint "antmicro-footprints:Torex_USP-6C"
		(layer "F.Cu")
		(at 154.125 141)
		(tags "Integrated Circuit")
		(property "Reference" "U40"
			(at 1.975 -0.05 90)
			(layer "F.SilkS")
			(effects
				(font
					(size 0.7 0.7)
					(thickness 0.254)
				)
			)
		)
		(property "Value" "XC6230H001ER-G"
			(at 0 2.8 0)
			(layer "F.Fab")
			(effects
				(font
					(size 1.27 1.27)
					(thickness 0.254)
				)
			)
		)
		(property "Description" "LDO Voltage Regulator, Adjustable, 1.7 V to 6 V in, 350 mV Drop, 1.188-1.212 V/2 A out, USP-6C-6"
			(at 0 0 0)
			(layer "F.Fab")
			(hide yes)
			(effects
				(font
					(size 1.27 1.27)
					(thickness 0.15)
				)
			)
		)
		(property "Author" "Antmicro"
			(at 0 0 0)
			(layer "F.Fab")
			(hide yes)
			(effects
				(font
					(size 1 1)
					(thickness 0.15)
				)
			)
		)
		(property "License" "Apache-2.0"
			(at 0 0 0)
			(layer "F.Fab")
			(hide yes)
			(effects
				(font
					(size 1 1)
					(thickness 0.15)
				)
			)
		)
		(property "MPN" "XC6230H001ER-G"
			(at 0 0 0)
			(layer "F.Fab")
			(hide yes)
			(effects
				(font
					(size 1 1)
					(thickness 0.15)
				)
			)
		)
		(property "Manufacturer" "Torex Semiconductor"
			(at 0 0 0)
			(layer "F.Fab")
			(hide yes)
			(effects
				(font
					(size 1 1)
					(thickness 0.15)
				)
			)
		)
		(sheetname "DC-DC Converters")
		(sheetfile "dc-dc.kicad_sch")
		(attr smd)
		(fp_circle
			(center -1.801 -0.554)
			(end -1.751 -0.554)
			(stroke
				(width 0.15)
				(type solid)
			)
			(fill yes)
			(layer "F.SilkS")
		)
		(fp_rect
			(start -0.403 -0.701)
			(end 0.4 -0.203)
			(stroke
				(width 0.01)
				(type solid)
			)
			(fill yes)
			(layer "F.Paste")
		)
		(fp_rect
			(start -0.403 0.2)
			(end 0.4 0.698)
			(stroke
				(width 0.01)
				(type solid)
			)
			(fill yes)
			(layer "F.Paste")
		)
		(fp_rect
			(start -1.5 -1.402)
			(end 1.498 1.4)
			(stroke
				(width 0.05)
				(type solid)
			)
			(fill no)
			(layer "F.CrtYd")
		)
		(fp_line
			(start -1 -0.903)
			(end 0.997 -0.903)
			(stroke
				(width 0.15)
				(type solid)
			)
			(layer "F.Fab")
		)
		(fp_line
			(start -1 -0.7)
			(end -0.8 -0.9)
			(stroke
				(width 0.15)
				(type solid)
			)
			(layer "F.Fab")
		)
		(fp_line
			(start -1 0.9)
			(end -1 -0.903)
			(stroke
				(width 0.15)
				(type solid)
			)
			(layer "F.Fab")
		)
		(fp_line
			(start 0.997 -0.903)
			(end 0.997 0.9)
			(stroke
				(width 0.15)
				(type solid)
			)
			(layer "F.Fab")
		)
		(fp_line
			(start 0.997 0.9)
			(end -1 0.9)
			(stroke
				(width 0.15)
				(type solid)
			)
			(layer "F.Fab")
		)
		(pad "1" smd rect
			(at -0.975 -0.553 90)
			(size 0.35 0.45)
			(layers "F.Cu" "F.Mask" "F.Paste")
			(net 748 "/DC-DC Converters/MGTAVTT_OUT")
			(pinfunction "OUT")
			(pintype "power_out")
		)
		(pad "2" smd rect
			(at -0.975 0 90)
			(size 0.25 0.45)
			(layers "F.Cu" "F.Mask" "F.Paste")
			(net 969 "/DC-DC Converters/MGTAVTT_ILIM")
			(pinfunction "ILIM")
			(pintype "output")
		)
		(pad "3" smd rect
			(at -0.975 0.497 90)
			(size 0.25 0.45)
			(layers "F.Cu" "F.Mask" "F.Paste")
			(net 748 "/DC-DC Converters/MGTAVTT_OUT")
			(pinfunction "FB")
			(pintype "open_collector")
		)
		(pad "4" smd rect
			(at 0.972 0.497 90)
			(size 0.25 0.45)
			(layers "F.Cu" "F.Mask" "F.Paste")
			(net 743 "/DC-DC Converters/1V7")
			(pinfunction "EN")
			(pintype "input")
		)
		(pad "5" smd rect
			(at 0.972 0 90)
			(size 0.25 0.45)
			(layers "F.Cu" "F.Mask" "F.Paste")
			(net 1 "GND")
			(pinfunction "GND")
			(pintype "power_in")
		)
		(pad "6" smd rect
			(at 0.972 -0.5 90)
			(size 0.25 0.45)
			(layers "F.Cu" "F.Mask" "F.Paste")
			(net 743 "/DC-DC Converters/1V7")
			(pinfunction "IN")
			(pintype "power_out")
		)
		(pad "7" smd rect
			(at 0 0)
			(size 1 1.6)
			(layers "F.Cu" "F.Mask")
			(net 1 "GND")
			(pinfunction "EP")
			(pintype "passive")
		)
		(pad "7" smd rect
			(at 0 0 90)
			(size 1.8 0.9)
			(layers "F.Cu" "F.Mask")
			(net 1 "GND")
			(pinfunction "EP")
			(pintype "passive")
		)
	)
)
